# BASEBOARD_FAB2 (Tioga Pass) — schematic netlist excerpt (pin names and nets, part order shuffled) for the footprints in the layout excerpt that follows; sources: Cadence DE-HDL packaged netlist, KiCad conversion of Wiwynn_Tioga_Pass_MB.brd

C1D33  CAP  0.22UF 16V 10% X7R  pkg 0402  page 209 : A = P5V_STBY ; B = GND
R12W3  4D02R2F-GP  1%  pkg SMD-RG2  page 197 : \1\ = P12V_STBY ; \2\ = P12V_NVDIMM_ABC_D
RF20  RES  1.0K 0.1% CHIP  pkg 0402  page 223 : A = VR_PVDDQ_GHJ_AIREF2 ; B = ISENSE_PVDDQ_GHJ_PH2_IMON

(kicad_pcb
	(version 20260206)
	(generator "pcbnew")
	(generator_version "10.0")
	(general
		(thickness 1.6)
		(legacy_teardrops no)
	)
	(paper "A4")
	(title_block
		(title "Wiwynn_Tioga_Pass_MB.brd")
		(comment 1 "Tioga Pass / footprints 2028-2030 of 4770")
	)
	(layers
		(0 "F.Cu" signal "TOP")
		(4 "In1.Cu" signal "L2GND")
		(6 "In2.Cu" signal "L3")
		(8 "In3.Cu" signal "L4GND")
		(10 "In4.Cu" signal "L5")
		(12 "In5.Cu" signal "L6GND")
		(14 "In6.Cu" signal "L7VCC")
		(16 "In7.Cu" signal "L8VCC")
		(18 "In8.Cu" signal "L9GND")
		(20 "In9.Cu" signal "L10")
		(22 "In10.Cu" signal "L11GND")
		(24 "In11.Cu" signal "L12")
		(26 "In12.Cu" signal "L13GND")
		(2 "B.Cu" signal "BOTTOM")
		(9 "F.Adhes" user "F.Adhesive")
		(11 "B.Adhes" user "B.Adhesive")
		(13 "F.Paste" user "Package Geometry/Pastemask Top")
		(15 "B.Paste" user "Package Geometry/Pastemask Bottom")
		(5 "F.SilkS" user "Ref Des/Silkscreen Top")
		(7 "B.SilkS" user "Ref Des/Silkscreen Bottom")
		(1 "F.Mask" user "Board Geometry/Soldermask Top")
		(3 "B.Mask" user "Board Geometry/Soldermask Bottom")
		(17 "Dwgs.User" user "User.Drawings")
		(19 "Cmts.User" user "User.Comments")
		(21 "Eco1.User" user "User.Eco1")
		(23 "Eco2.User" user "User.Eco2")
		(25 "Edge.Cuts" user "Board Geometry/Outline")
		(27 "Margin" user)
		(31 "F.CrtYd" user "Package Geometry/Place Bound Top")
		(29 "B.CrtYd" user "Package Geometry/Place Bound Bottom")
		(35 "F.Fab" user "Ref Des/Assembly Top")
		(33 "B.Fab" user "Ref Des/Assembly Bottom")
	)
	(footprint ""
		(layer "F.Cu")
		(at 178.36261 -24.961088 90)
		(property "Reference" "R12W3"
			(at 0 0 90)
			(layer "F.SilkS")
			(hide yes)
			(effects
				(font
					(size 1.27 1.27)
				)
			)
		)
		(property "Value" "*"
			(at 0.064008 -4.108196 90)
			(unlocked yes)
			(layer "F.Fab")
			(hide yes)
			(effects
				(font
					(size 1.27 1.016)
					(thickness 0.1524)
				)
			)
		)
		(property "Device Type" "4D02R2F-GP_SMD-RG2-4D02R2F-GP,A"
			(at 0.064008 -5.632196 90)
			(unlocked yes)
			(layer "F.Fab")
			(hide yes)
			(effects
				(font
					(size 1.27 1.016)
					(thickness 0.1524)
				)
			)
		)
		(duplicate_pad_numbers_are_jumpers no)
		(fp_line
			(start 0.508 -0.9398)
			(end -0.508 -0.9398)
			(stroke
				(width 0.1524)
				(type default)
			)
			(layer "F.SilkS")
		)
		(fp_line
			(start -0.508 -0.9398)
			(end -0.508 0.9398)
			(stroke
				(width 0.1524)
				(type default)
			)
			(layer "F.SilkS")
		)
		(fp_rect
			(start -0.508 0.9398)
			(end 0.508 -0.9398)
			(stroke
				(width 0)
				(type default)
			)
			(fill no)
			(layer "F.CrtYd")
		)
		(fp_rect
			(start -0.508 0.9398)
			(end 0.508 -0.9398)
			(stroke
				(width 0)
				(type default)
			)
			(fill no)
			(layer "F.Fab")
		)
		(pad "1" smd custom
			(at 0 -0.4445 90)
			(size 0.1397 0.1397)
			(layers "F.Cu" "F.Mask" "F.Paste")
			(net "P12V_STBY")
			(options
				(clearance outline)
				(anchor circle)
			)
			(primitives
				(gr_poly
					(pts
						(arc
							(start -0.1778 -0.2794)
							(mid -0.249642 -0.249642)
							(end -0.2794 -0.1778)
						)
						(arc
							(start -0.2794 0.1778)
							(mid -0.249642 0.249642)
							(end -0.1778 0.2794)
						)
						(arc
							(start 0.1778 0.2794)
							(mid 0.249642 0.249642)
							(end 0.2794 0.1778)
						)
						(arc
							(start 0.2794 -0.1778)
							(mid 0.249642 -0.249642)
							(end 0.1778 -0.2794)
						)
					)
					(width 0)
					(fill yes)
				)
			)
		)
		(pad "2" smd custom
			(at 0 0.4445 90)
			(size 0.1397 0.1397)
			(layers "F.Cu" "F.Mask" "F.Paste")
			(net "P12V_NVDIMM_ABC_D")
			(options
				(clearance outline)
				(anchor circle)
			)
			(primitives
				(gr_poly
					(pts
						(arc
							(start -0.1778 -0.2794)
							(mid -0.249642 -0.249642)
							(end -0.2794 -0.1778)
						)
						(arc
							(start -0.2794 0.1778)
							(mid -0.249642 0.249642)
							(end -0.1778 0.2794)
						)
						(arc
							(start 0.1778 0.2794)
							(mid 0.249642 0.249642)
							(end 0.2794 0.1778)
						)
						(arc
							(start 0.2794 -0.1778)
							(mid 0.249642 -0.249642)
							(end 0.1778 -0.2794)
						)
					)
					(width 0)
					(fill yes)
				)
			)
		)
	)
	(footprint ""
		(layer "F.Cu")
		(at 5.602732 2.141474 90)
		(property "Reference" "RF20"
			(at -0.8382 -0.67818 90)
			(unlocked yes)
			(layer "F.SilkS")
			(effects
				(font
					(size 0.4064 0.254)
					(thickness 0.1524)
				)
				(justify left)
			)
		)
		(property "Value" ""
			(at 0 0 90)
			(layer "F.Fab")
			(effects
				(font
					(size 1.27 1.27)
				)
			)
		)
		(duplicate_pad_numbers_are_jumpers no)
		(fp_poly
			(pts
				(xy -0.2794 -0.1016) (xy 0.2794 -0.1016) (xy 0.2794 0.9906) (xy -0.2794 0.9906)
			)
			(stroke
				(width 0)
				(type default)
			)
			(fill no)
			(layer "F.CrtYd")
		)
		(fp_line
			(start 0.2794 -0.1016)
			(end -0.2794 -0.1016)
			(stroke
				(width 0.1)
				(type default)
			)
			(layer "F.Fab")
		)
		(fp_line
			(start -0.2794 -0.1016)
			(end -0.2794 0.9906)
			(stroke
				(width 0.1)
				(type default)
			)
			(layer "F.Fab")
		)
		(fp_line
			(start 0.2794 0.9906)
			(end 0.2794 -0.1016)
			(stroke
				(width 0.1)
				(type default)
			)
			(layer "F.Fab")
		)
		(fp_line
			(start -0.2794 0.9906)
			(end 0.2794 0.9906)
			(stroke
				(width 0.1)
				(type default)
			)
			(layer "F.Fab")
		)
		(pad "1" smd rect
			(at 0 0 90)
			(size 0.508 0.508)
			(layers "F.Cu" "F.Mask" "F.Paste")
			(net "VR_PVDDQ_GHJ_AIREF2")
		)
		(pad "2" smd rect
			(at 0 0.889 90)
			(size 0.508 0.508)
			(layers "F.Cu" "F.Mask" "F.Paste")
			(net "ISENSE_PVDDQ_GHJ_PH2_IMON")
		)
		(zone
			(layer "F.Cu")
			(hatch none 0.5)
			(connect_pads
				(clearance 0)
			)
			(min_thickness 0.25)
			(keepout
				(tracks allowed)
				(vias not_allowed)
				(pads allowed)
				(copperpour not_allowed)
				(footprints allowed)
			)
			(placement
				(enabled no)
				(sheetname "")
			)
			(fill
				(thermal_gap 0.5)
				(thermal_bridge_width 0.5)
				(island_removal_mode 0)
			)
			(polygon
				(pts
					(xy 5.856732 2.395474) (xy 5.856732 1.887474) (xy 6.237732 1.887474) (xy 6.237732 2.395474)
				)
			)
		)
		(zone
			(layer "F.Cu")
			(hatch none 0.5)
			(connect_pads
				(clearance 0)
			)
			(min_thickness 0.25)
			(keepout
				(tracks not_allowed)
				(vias allowed)
				(pads allowed)
				(copperpour not_allowed)
				(footprints allowed)
			)
			(placement
				(enabled no)
				(sheetname "")
			)
			(fill
				(thermal_gap 0.5)
				(thermal_bridge_width 0.5)
				(island_removal_mode 0)
			)
			(polygon
				(pts
					(xy 6.237732 2.395474) (xy 6.237732 1.887474) (xy 5.856732 1.887474) (xy 5.856732 2.395474)
				)
			)
		)
	)
	(footprint ""
		(layer "F.Cu")
		(at 33.278826 -85.7377 90)
		(property "Reference" "C1D33"
			(at 0 0 90)
			(layer "F.SilkS")
			(hide yes)
			(effects
				(font
					(size 1.27 1.27)
				)
			)
		)
		(property "Value" ""
			(at 0 0 90)
			(layer "F.Fab")
			(effects
				(font
					(size 1.27 1.27)
				)
			)
		)
		(duplicate_pad_numbers_are_jumpers no)
		(fp_rect
			(start 0.3048 0.9906)
			(end -0.3048 -0.1016)
			(stroke
				(width 0)
				(type default)
			)
			(fill no)
			(layer "F.CrtYd")
		)
		(fp_line
			(start 0.3048 -0.1016)
			(end -0.3048 -0.1016)
			(stroke
				(width 0.1)
				(type default)
			)
			(layer "F.Fab")
		)
		(fp_line
			(start -0.3048 -0.1016)
			(end -0.3048 0.9906)
			(stroke
				(width 0.1)
				(type default)
			)
			(layer "F.Fab")
		)
		(fp_line
			(start 0.3048 0.9906)
			(end 0.3048 -0.1016)
			(stroke
				(width 0.1)
				(type default)
			)
			(layer "F.Fab")
		)
		(fp_line
			(start -0.3048 0.9906)
			(end 0.3048 0.9906)
			(stroke
				(width 0.1)
				(type default)
			)
			(layer "F.Fab")
		)
		(pad "1" smd rect
			(at 0 0 90)
			(size 0.508 0.508)
			(layers "F.Cu" "F.Mask" "F.Paste")
			(net "P5V_STBY")
		)
		(pad "2" smd rect
			(at 0 0.889 90)
			(size 0.508 0.508)
			(layers "F.Cu" "F.Mask" "F.Paste")
			(net "GND")
		)
		(zone
			(layer "F.Cu")
			(hatch none 0.5)
			(connect_pads
				(clearance 0)
			)
			(min_thickness 0.25)
			(keepout
				(tracks not_allowed)
				(vias allowed)
				(pads allowed)
				(copperpour not_allowed)
				(footprints allowed)
			)
			(placement
				(enabled no)
				(sheetname "")
			)
			(fill
				(thermal_gap 0.5)
				(thermal_bridge_width 0.5)
				(island_removal_mode 0)
			)
			(polygon
				(pts
					(xy 33.913826 -85.9917) (xy 33.532826 -85.9917) (xy 33.532826 -85.4837) (xy 33.913826 -85.4837)
				)
			)
		)
		(zone
			(layer "F.Cu")
			(hatch none 0.5)
			(connect_pads
				(clearance 0)
			)
			(min_thickness 0.25)
			(keepout
				(tracks allowed)
				(vias not_allowed)
				(pads allowed)
				(copperpour not_allowed)
				(footprints allowed)
			)
			(placement
				(enabled no)
				(sheetname "")
			)
			(fill
				(thermal_gap 0.5)
				(thermal_bridge_width 0.5)
				(island_removal_mode 0)
			)
			(polygon
				(pts
					(xy 33.913826 -85.9917) (xy 33.532826 -85.9917) (xy 33.532826 -85.4837) (xy 33.913826 -85.4837)
				)
			)
		)
	)
)
